(kicad_pcb
	(version 20260206)
	(generator "pcbnew")
	(generator_version "10.0")
	(general
		(thickness 1.6)
		(legacy_teardrops no)
	)
	(paper "A4")
	(title_block
		(title "baseboard — 13948-1b.1110WZS1818.brd")
		(comment 1 "Honey Badger (Wiwynn) / footprints 899-905 of 2523")
	)
	(layers
		(0 "F.Cu" signal "TOP")
		(4 "In1.Cu" signal "L2GND")
		(6 "In2.Cu" signal "L3")
		(8 "In3.Cu" signal "L4VCC")
		(10 "In4.Cu" signal "L5VCC")
		(12 "In5.Cu" signal "L6")
		(14 "In6.Cu" signal "L7GND")
		(2 "B.Cu" signal "BOTTOM")
		(9 "F.Adhes" user "F.Adhesive")
		(11 "B.Adhes" user "B.Adhesive")
		(13 "F.Paste" user "Package Geometry/Pastemask Top")
		(15 "B.Paste" user "Package Geometry/Pastemask Bottom")
		(5 "F.SilkS" user "Ref Des/Silkscreen Top")
		(7 "B.SilkS" user "Ref Des/Silkscreen Bottom")
		(1 "F.Mask" user "Board Geometry/Soldermask Top")
		(3 "B.Mask" user "Board Geometry/Soldermask Bottom")
		(17 "Dwgs.User" user "User.Drawings")
		(19 "Cmts.User" user "User.Comments")
		(21 "Eco1.User" user "User.Eco1")
		(23 "Eco2.User" user "User.Eco2")
		(25 "Edge.Cuts" user "Board Geometry/Outline")
		(27 "Margin" user)
		(31 "F.CrtYd" user "Package Geometry/Place Bound Top")
		(29 "B.CrtYd" user "Package Geometry/Place Bound Bottom")
		(35 "F.Fab" user "Ref Des/Assembly Top")
		(33 "B.Fab" user "Ref Des/Assembly Bottom")
	)
	(footprint ""
		(layer "F.Cu")
		(at 195.014596 -113.811812 90)
		(property "Reference" "PR9019"
			(at 0 0 90)
			(layer "F.SilkS")
			(hide yes)
			(effects
				(font
					(size 1.27 1.27)
				)
			)
		)
		(property "Value" "3D01R5F-GP"
			(at 0 -8.9535 90)
			(unlocked yes)
			(layer "F.Fab")
			(hide yes)
			(effects
				(font
					(size 1.27 1.016)
					(thickness 0.1524)
				)
			)
		)
		(property "Device Type" "R805H24"
			(at 0 -10.6299 90)
			(unlocked yes)
			(layer "F.Fab")
			(hide yes)
			(effects
				(font
					(size 1.27 1.016)
					(thickness 0.1524)
				)
			)
		)
		(duplicate_pad_numbers_are_jumpers no)
		(fp_line
			(start 0.889 -1.7018)
			(end -0.889 -1.7018)
			(stroke
				(width 0.1524)
				(type default)
			)
			(layer "F.SilkS")
		)
		(fp_line
			(start 0.889 -1.7018)
			(end 0.889 -0.381)
			(stroke
				(width 0.1524)
				(type default)
			)
			(layer "F.SilkS")
		)
		(fp_line
			(start -0.889 -1.7018)
			(end -0.889 0.2794)
			(stroke
				(width 0.1524)
				(type default)
			)
			(layer "F.SilkS")
		)
		(fp_line
			(start -0.889 0.0762)
			(end -0.889 1.7018)
			(stroke
				(width 0.1524)
				(type default)
			)
			(layer "F.SilkS")
		)
		(fp_line
			(start 0.889 1.7018)
			(end 0.889 -0.508)
			(stroke
				(width 0.1524)
				(type default)
			)
			(layer "F.SilkS")
		)
		(fp_line
			(start -0.889 1.7018)
			(end 0.889 1.7018)
			(stroke
				(width 0.1524)
				(type default)
			)
			(layer "F.SilkS")
		)
		(fp_poly
			(pts
				(xy 0.9652 -1.778) (xy 0.9652 1.778) (xy -0.9652 1.778) (xy -0.9652 -1.778)
			)
			(stroke
				(width 0)
				(type default)
			)
			(fill no)
			(layer "F.CrtYd")
		)
		(fp_rect
			(start -0.9652 1.778)
			(end 0.9652 -1.778)
			(stroke
				(width 0)
				(type default)
			)
			(fill no)
			(layer "F.Fab")
		)
		(pad "1" smd rect
			(at 0 -0.9652 90)
			(size 1.397 1.143)
			(layers "F.Cu" "F.Mask" "F.Paste")
			(net "P1V5_E_SNB")
		)
		(pad "2" smd rect
			(at 0 0.9652 90)
			(size 1.397 1.143)
			(layers "F.Cu" "F.Mask" "F.Paste")
			(net "GND")
		)
	)
	(footprint ""
		(layer "F.Cu")
		(at 340.262718 -142.852648 -90)
		(property "Reference" "C8091"
			(at 0 0 270)
			(layer "F.SilkS")
			(hide yes)
			(effects
				(font
					(size 1.27 1.27)
				)
			)
		)
		(property "Value" "SC18P50V3JN-1-GP"
			(at 0 -2.8194 270)
			(unlocked yes)
			(layer "F.Fab")
			(hide yes)
			(effects
				(font
					(size 1.016 1.016)
					(thickness 0.1524)
				)
			)
		)
		(property "Device Type" "C603"
			(at 0 -4.3434 270)
			(unlocked yes)
			(layer "F.Fab")
			(hide yes)
			(effects
				(font
					(size 1.016 1.016)
					(thickness 0.1524)
				)
			)
		)
		(duplicate_pad_numbers_are_jumpers no)
		(fp_line
			(start 0.508 0)
			(end -0.508 0)
			(stroke
				(width 0.2032)
				(type default)
			)
			(layer "F.SilkS")
		)
		(fp_rect
			(start -0.5842 1.3335)
			(end 0.5842 -1.3335)
			(stroke
				(width 0)
				(type default)
			)
			(fill no)
			(layer "F.CrtYd")
		)
		(fp_rect
			(start -0.5842 1.3335)
			(end 0.5842 -1.3335)
			(stroke
				(width 0)
				(type default)
			)
			(fill no)
			(layer "F.Fab")
		)
		(pad "1" smd custom
			(at 0 -0.762 270)
			(size 0.2159 0.2159)
			(layers "F.Cu" "F.Mask" "F.Paste")
			(net "USB_HUB_XTAL_OUT")
			(options
				(clearance outline)
				(anchor circle)
			)
			(primitives
				(gr_poly
					(pts
						(arc
							(start -0.3302 -0.4318)
							(mid -0.402042 -0.402042)
							(end -0.4318 -0.3302)
						)
						(arc
							(start -0.4318 0.3302)
							(mid -0.402042 0.402042)
							(end -0.3302 0.4318)
						)
						(arc
							(start 0.3302 0.4318)
							(mid 0.402042 0.402042)
							(end 0.4318 0.3302)
						)
						(arc
							(start 0.4318 -0.3302)
							(mid 0.402042 -0.402042)
							(end 0.3302 -0.4318)
						)
					)
					(width 0)
					(fill yes)
				)
			)
		)
		(pad "2" smd custom
			(at 0 0.762 270)
			(size 0.2159 0.2159)
			(layers "F.Cu" "F.Mask" "F.Paste")
			(net "GND")
			(options
				(clearance outline)
				(anchor circle)
			)
			(primitives
				(gr_poly
					(pts
						(arc
							(start -0.3302 -0.4318)
							(mid -0.402042 -0.402042)
							(end -0.4318 -0.3302)
						)
						(arc
							(start -0.4318 0.3302)
							(mid -0.402042 0.402042)
							(end -0.3302 0.4318)
						)
						(arc
							(start 0.3302 0.4318)
							(mid 0.402042 0.402042)
							(end 0.4318 0.3302)
						)
						(arc
							(start 0.4318 -0.3302)
							(mid 0.402042 -0.402042)
							(end 0.3302 -0.4318)
						)
					)
					(width 0)
					(fill yes)
				)
			)
		)
	)
	(footprint ""
		(layer "F.Cu")
		(at 300.99 -219.837)
		(property "Reference" "PQ7"
			(at 0 0 0)
			(layer "F.SilkS")
			(hide yes)
			(effects
				(font
					(size 1.27 1.27)
				)
			)
		)
		(property "Value" "2N7002A-7-GP"
			(at 0.127 -8.9662 0)
			(unlocked yes)
			(layer "F.Fab")
			(hide yes)
			(effects
				(font
					(size 1.016 1.016)
					(thickness 0.1524)
				)
			)
		)
		(property "Device Type" "SOT23DGS2D4H48"
			(at 0.127 -10.4902 0)
			(unlocked yes)
			(layer "F.Fab")
			(hide yes)
			(effects
				(font
					(size 1.016 1.016)
					(thickness 0.1524)
				)
			)
		)
		(duplicate_pad_numbers_are_jumpers no)
		(fp_line
			(start -1.651 -1.778)
			(end -1.651 1.778)
			(stroke
				(width 0.1524)
				(type default)
			)
			(layer "F.SilkS")
		)
		(fp_line
			(start -1.651 1.778)
			(end 1.651 1.778)
			(stroke
				(width 0.1524)
				(type default)
			)
			(layer "F.SilkS")
		)
		(fp_line
			(start 1.651 -1.778)
			(end -1.651 -1.778)
			(stroke
				(width 0.1524)
				(type default)
			)
			(layer "F.SilkS")
		)
		(fp_line
			(start 1.651 1.778)
			(end 1.651 -1.778)
			(stroke
				(width 0.1524)
				(type default)
			)
			(layer "F.SilkS")
		)
		(fp_poly
			(pts
				(xy -1.778 1.8796) (xy -1.778 -1.8796) (xy 1.778 -1.8796) (xy 1.778 1.8796)
			)
			(stroke
				(width 0)
				(type default)
			)
			(fill no)
			(layer "F.CrtYd")
		)
		(fp_poly
			(pts
				(xy -1.778 1.8796) (xy -1.778 -1.8796) (xy 1.778 -1.8796) (xy 1.778 1.8796)
			)
			(stroke
				(width 0)
				(type default)
			)
			(fill no)
			(layer "F.Fab")
		)
		(pad "D" smd custom
			(at 0 -0.9525)
			(size 0.1905 0.1905)
			(layers "F.Cu" "F.Mask" "F.Paste")
			(net "DEBUG_OE_1_N")
			(options
				(clearance outline)
				(anchor circle)
			)
			(primitives
				(gr_poly
					(pts
						(arc
							(start -0.1778 0.5715)
							(mid -0.321484 0.511984)
							(end -0.381 0.3683)
						)
						(arc
							(start -0.381 -0.3683)
							(mid -0.321484 -0.511984)
							(end -0.1778 -0.5715)
						)
						(arc
							(start 0.1778 -0.5715)
							(mid 0.321484 -0.511984)
							(end 0.381 -0.3683)
						)
						(arc
							(start 0.381 0.3683)
							(mid 0.321484 0.511984)
							(end 0.1778 0.5715)
						)
					)
					(width 0)
					(fill yes)
				)
			)
		)
		(pad "G" smd custom
			(at -0.98425 0.9525)
			(size 0.1905 0.1905)
			(layers "F.Cu" "F.Mask" "F.Paste")
			(net "PMU_PLTRST_N")
			(options
				(clearance outline)
				(anchor circle)
			)
			(primitives
				(gr_poly
					(pts
						(arc
							(start -0.1778 0.5715)
							(mid -0.321484 0.511984)
							(end -0.381 0.3683)
						)
						(arc
							(start -0.381 -0.3683)
							(mid -0.321484 -0.511984)
							(end -0.1778 -0.5715)
						)
						(arc
							(start 0.1778 -0.5715)
							(mid 0.321484 -0.511984)
							(end 0.381 -0.3683)
						)
						(arc
							(start 0.381 0.3683)
							(mid 0.321484 0.511984)
							(end 0.1778 0.5715)
						)
					)
					(width 0)
					(fill yes)
				)
			)
		)
		(pad "S" smd custom
			(at 0.98425 0.9525)
			(size 0.1905 0.1905)
			(layers "F.Cu" "F.Mask" "F.Paste")
			(net "GND")
			(options
				(clearance outline)
				(anchor circle)
			)
			(primitives
				(gr_poly
					(pts
						(arc
							(start -0.1778 0.5715)
							(mid -0.321484 0.511984)
							(end -0.381 0.3683)
						)
						(arc
							(start -0.381 -0.3683)
							(mid -0.321484 -0.511984)
							(end -0.1778 -0.5715)
						)
						(arc
							(start 0.1778 -0.5715)
							(mid 0.321484 -0.511984)
							(end 0.381 -0.3683)
						)
						(arc
							(start 0.381 0.3683)
							(mid 0.321484 0.511984)
							(end 0.1778 0.5715)
						)
					)
					(width 0)
					(fill yes)
				)
			)
		)
	)
	(footprint ""
		(layer "F.Cu")
		(at 23.064216 -200.71588 90)
		(property "Reference" "R564"
			(at 0 0 90)
			(layer "F.SilkS")
			(hide yes)
			(effects
				(font
					(size 1.27 1.27)
				)
			)
		)
		(property "Value" "0R2J-2-GP"
			(at 0.064008 -3.993896 90)
			(unlocked yes)
			(layer "F.Fab")
			(hide yes)
			(effects
				(font
					(size 1.016 1.016)
					(thickness 0.1524)
				)
			)
		)
		(property "Device Type" "R402H16"
			(at 0.064008 -5.517896 90)
			(unlocked yes)
			(layer "F.Fab")
			(hide yes)
			(effects
				(font
					(size 1.016 1.016)
					(thickness 0.1524)
				)
			)
		)
		(duplicate_pad_numbers_are_jumpers no)
		(fp_line
			(start 0.508 -0.9398)
			(end -0.508 -0.9398)
			(stroke
				(width 0.1524)
				(type default)
			)
			(layer "F.SilkS")
		)
		(fp_line
			(start -0.508 -0.9398)
			(end -0.508 0.9398)
			(stroke
				(width 0.1524)
				(type default)
			)
			(layer "F.SilkS")
		)
		(fp_rect
			(start -0.508 0.9398)
			(end 0.508 -0.9398)
			(stroke
				(width 0)
				(type default)
			)
			(fill no)
			(layer "F.CrtYd")
		)
		(fp_rect
			(start -0.508 0.9398)
			(end 0.508 -0.9398)
			(stroke
				(width 0)
				(type default)
			)
			(fill no)
			(layer "F.Fab")
		)
		(pad "1" smd custom
			(at 0 -0.4445 90)
			(size 0.1397 0.1397)
			(layers "F.Cu" "F.Mask" "F.Paste")
			(net "ADC_P0V955_C")
			(options
				(clearance outline)
				(anchor circle)
			)
			(primitives
				(gr_poly
					(pts
						(arc
							(start -0.1778 -0.2794)
							(mid -0.249642 -0.249642)
							(end -0.2794 -0.1778)
						)
						(arc
							(start -0.2794 0.1778)
							(mid -0.249642 0.249642)
							(end -0.1778 0.2794)
						)
						(arc
							(start 0.1778 0.2794)
							(mid 0.249642 0.249642)
							(end 0.2794 0.1778)
						)
						(arc
							(start 0.2794 -0.1778)
							(mid 0.249642 -0.249642)
							(end 0.1778 -0.2794)
						)
					)
					(width 0)
					(fill yes)
				)
			)
		)
		(pad "2" smd custom
			(at 0 0.4445 90)
			(size 0.1397 0.1397)
			(layers "F.Cu" "F.Mask" "F.Paste")
			(net "P0V955_C_SENSE")
			(options
				(clearance outline)
				(anchor circle)
			)
			(primitives
				(gr_poly
					(pts
						(arc
							(start -0.1778 -0.2794)
							(mid -0.249642 -0.249642)
							(end -0.2794 -0.1778)
						)
						(arc
							(start -0.2794 0.1778)
							(mid -0.249642 0.249642)
							(end -0.1778 0.2794)
						)
						(arc
							(start 0.1778 0.2794)
							(mid 0.249642 0.249642)
							(end 0.2794 0.1778)
						)
						(arc
							(start 0.2794 -0.1778)
							(mid 0.249642 -0.249642)
							(end 0.1778 -0.2794)
						)
					)
					(width 0)
					(fill yes)
				)
			)
		)
	)
	(footprint ""
		(layer "F.Cu")
		(at 184.776872 -198.496936 180)
		(property "Reference" "C243"
			(at 0 0 180)
			(layer "F.SilkS")
			(hide yes)
			(effects
				(font
					(size 1.27 1.27)
				)
			)
		)
		(property "Value" "SCD1U16V2KX-3GP"
			(at 1.1811 -2.7051 180)
			(unlocked yes)
			(layer "F.Fab")
			(hide yes)
			(effects
				(font
					(size 1.016 1.016)
					(thickness 0.1524)
				)
			)
		)
		(property "Device Type" "C402H22"
			(at 1.1811 -4.2291 180)
			(unlocked yes)
			(layer "F.Fab")
			(hide yes)
			(effects
				(font
					(size 1.016 1.016)
					(thickness 0.1524)
				)
			)
		)
		(duplicate_pad_numbers_are_jumpers no)
		(fp_rect
			(start -0.4318 0.9525)
			(end 0.4318 -0.9525)
			(stroke
				(width 0)
				(type default)
			)
			(fill no)
			(layer "F.CrtYd")
		)
		(fp_rect
			(start -0.4318 0.9525)
			(end 0.4318 -0.9525)
			(stroke
				(width 0)
				(type default)
			)
			(fill no)
			(layer "F.Fab")
		)
		(pad "1" smd custom
			(at 0 -0.4445 180)
			(size 0.1524 0.1524)
			(layers "F.Cu" "F.Mask" "F.Paste")
			(net "P3V3_STBY")
			(options
				(clearance outline)
				(anchor circle)
			)
			(primitives
				(gr_poly
					(pts
						(arc
							(start 0.3048 -0.2032)
							(mid 0.275042 -0.275042)
							(end 0.2032 -0.3048)
						)
						(arc
							(start -0.2032 -0.3048)
							(mid -0.275042 -0.275042)
							(end -0.3048 -0.2032)
						)
						(arc
							(start -0.3048 0.2032)
							(mid -0.275042 0.275042)
							(end -0.2032 0.3048)
						)
						(arc
							(start 0.2032 0.3048)
							(mid 0.275042 0.275042)
							(end 0.3048 0.2032)
						)
					)
					(width 0)
					(fill yes)
				)
			)
		)
		(pad "2" smd custom
			(at 0 0.4445 180)
			(size 0.1524 0.1524)
			(layers "F.Cu" "F.Mask" "F.Paste")
			(net "GND")
			(options
				(clearance outline)
				(anchor circle)
			)
			(primitives
				(gr_poly
					(pts
						(arc
							(start 0.3048 -0.2032)
							(mid 0.275042 -0.275042)
							(end 0.2032 -0.3048)
						)
						(arc
							(start -0.2032 -0.3048)
							(mid -0.275042 -0.275042)
							(end -0.3048 -0.2032)
						)
						(arc
							(start -0.3048 0.2032)
							(mid -0.275042 0.275042)
							(end -0.2032 0.3048)
						)
						(arc
							(start 0.2032 0.3048)
							(mid 0.275042 0.275042)
							(end 0.3048 0.2032)
						)
					)
					(width 0)
					(fill yes)
				)
			)
		)
	)
	(footprint ""
		(layer "F.Cu")
		(at 176.012348 -113.401856 180)
		(property "Reference" "PR154"
			(at 0 0 180)
			(layer "F.SilkS")
			(hide yes)
			(effects
				(font
					(size 1.27 1.27)
				)
			)
		)
		(property "Value" "3D01R5F-GP"
			(at 0 -8.9535 180)
			(unlocked yes)
			(layer "F.Fab")
			(hide yes)
			(effects
				(font
					(size 1.27 1.016)
					(thickness 0.1524)
				)
			)
		)
		(property "Device Type" "R805H24"
			(at 0 -10.6299 180)
			(unlocked yes)
			(layer "F.Fab")
			(hide yes)
			(effects
				(font
					(size 1.27 1.016)
					(thickness 0.1524)
				)
			)
		)
		(duplicate_pad_numbers_are_jumpers no)
		(fp_line
			(start 0.889 1.7018)
			(end 0.889 -0.508)
			(stroke
				(width 0.1524)
				(type default)
			)
			(layer "F.SilkS")
		)
		(fp_line
			(start 0.889 -1.7018)
			(end 0.889 -0.381)
			(stroke
				(width 0.1524)
				(type default)
			)
			(layer "F.SilkS")
		)
		(fp_line
			(start 0.889 -1.7018)
			(end -0.889 -1.7018)
			(stroke
				(width 0.1524)
				(type default)
			)
			(layer "F.SilkS")
		)
		(fp_line
			(start -0.889 1.7018)
			(end 0.889 1.7018)
			(stroke
				(width 0.1524)
				(type default)
			)
			(layer "F.SilkS")
		)
		(fp_line
			(start -0.889 0.0762)
			(end -0.889 1.7018)
			(stroke
				(width 0.1524)
				(type default)
			)
			(layer "F.SilkS")
		)
		(fp_line
			(start -0.889 -1.7018)
			(end -0.889 0.2794)
			(stroke
				(width 0.1524)
				(type default)
			)
			(layer "F.SilkS")
		)
		(fp_poly
			(pts
				(xy 0.9652 -1.778) (xy 0.9652 1.778) (xy -0.9652 1.778) (xy -0.9652 -1.778)
			)
			(stroke
				(width 0)
				(type default)
			)
			(fill no)
			(layer "F.CrtYd")
		)
		(fp_rect
			(start -0.9652 1.778)
			(end 0.9652 -1.778)
			(stroke
				(width 0)
				(type default)
			)
			(fill no)
			(layer "F.Fab")
		)
		(pad "1" smd rect
			(at 0 -0.9652 180)
			(size 1.397 1.143)
			(layers "F.Cu" "F.Mask" "F.Paste")
			(net "P0V9_E_LX")
		)
		(pad "2" smd rect
			(at 0 0.9652 180)
			(size 1.397 1.143)
			(layers "F.Cu" "F.Mask" "F.Paste")
			(net "P0V9_E_SNB")
		)
	)
	(footprint ""
		(layer "F.Cu")
		(at 19.381216 -225.98888 90)
		(property "Reference" "R634"
			(at 0 0 90)
			(layer "F.SilkS")
			(hide yes)
			(effects
				(font
					(size 1.27 1.27)
				)
			)
		)
		(property "Value" "4K7R2F-GP"
			(at 0.064008 -3.993896 90)
			(unlocked yes)
			(layer "F.Fab")
			(hide yes)
			(effects
				(font
					(size 1.016 1.016)
					(thickness 0.1524)
				)
			)
		)
		(property "Device Type" "R402H16"
			(at 0.064008 -5.517896 90)
			(unlocked yes)
			(layer "F.Fab")
			(hide yes)
			(effects
				(font
					(size 1.016 1.016)
					(thickness 0.1524)
				)
			)
		)
		(duplicate_pad_numbers_are_jumpers no)
		(fp_line
			(start 0.508 -0.9398)
			(end -0.508 -0.9398)
			(stroke
				(width 0.1524)
				(type default)
			)
			(layer "F.SilkS")
		)
		(fp_line
			(start -0.508 -0.9398)
			(end -0.508 0.9398)
			(stroke
				(width 0.1524)
				(type default)
			)
			(layer "F.SilkS")
		)
		(fp_rect
			(start -0.508 0.9398)
			(end 0.508 -0.9398)
			(stroke
				(width 0)
				(type default)
			)
			(fill no)
			(layer "F.CrtYd")
		)
		(fp_rect
			(start -0.508 0.9398)
			(end 0.508 -0.9398)
			(stroke
				(width 0)
				(type default)
			)
			(fill no)
			(layer "F.Fab")
		)
		(pad "1" smd custom
			(at 0 -0.4445 90)
			(size 0.1397 0.1397)
			(layers "F.Cu" "F.Mask" "F.Paste")
			(net "IO_EXP_HDD_PWR_A3")
			(options
				(clearance outline)
				(anchor circle)
			)
			(primitives
				(gr_poly
					(pts
						(arc
							(start -0.1778 -0.2794)
							(mid -0.249642 -0.249642)
							(end -0.2794 -0.1778)
						)
						(arc
							(start -0.2794 0.1778)
							(mid -0.249642 0.249642)
							(end -0.1778 0.2794)
						)
						(arc
							(start 0.1778 0.2794)
							(mid 0.249642 0.249642)
							(end 0.2794 0.1778)
						)
						(arc
							(start 0.2794 -0.1778)
							(mid 0.249642 -0.249642)
							(end 0.1778 -0.2794)
						)
					)
					(width 0)
					(fill yes)
				)
			)
		)
		(pad "2" smd custom
			(at 0 0.4445 90)
			(size 0.1397 0.1397)
			(layers "F.Cu" "F.Mask" "F.Paste")
			(net "GND")
			(options
				(clearance outline)
				(anchor circle)
			)
			(primitives
				(gr_poly
					(pts
						(arc
							(start -0.1778 -0.2794)
							(mid -0.249642 -0.249642)
							(end -0.2794 -0.1778)
						)
						(arc
							(start -0.2794 0.1778)
							(mid -0.249642 0.249642)
							(end -0.1778 0.2794)
						)
						(arc
							(start 0.1778 0.2794)
							(mid 0.249642 0.249642)
							(end 0.2794 0.1778)
						)
						(arc
							(start 0.2794 -0.1778)
							(mid 0.249642 -0.249642)
							(end 0.1778 -0.2794)
						)
					)
					(width 0)
					(fill yes)
				)
			)
		)
	)
)
